(kicad_pcb
	(version 20260206)
	(generator "pcbnew")
	(generator_version "10.0")
	(general
		(thickness 1.6)
		(legacy_teardrops no)
	)
	(paper "A4")
	(title_block
		(title "01162023_DA0F0TEBIF0_F0T_Expander_BD_F_brd_V02_OCP.brd")
		(comment 1 "Grand Teton / footprints 8664-8671 of 9728")
	)
	(layers
		(0 "F.Cu" signal "TOP")
		(4 "In1.Cu" signal "GND")
		(6 "In2.Cu" signal "VCC")
		(8 "In3.Cu" signal "VCC1")
		(10 "In4.Cu" signal "GND1")
		(12 "In5.Cu" signal "IN1")
		(14 "In6.Cu" signal "GND2")
		(16 "In7.Cu" signal "IN2")
		(18 "In8.Cu" signal "GND3")
		(20 "In9.Cu" signal "IN3")
		(22 "In10.Cu" signal "GND4")
		(24 "In11.Cu" signal "IN4")
		(26 "In12.Cu" signal "GND5")
		(28 "In13.Cu" signal "IN5")
		(30 "In14.Cu" signal "GND6")
		(32 "In15.Cu" signal "IN6")
		(34 "In16.Cu" signal "GND7")
		(2 "B.Cu" signal "BOTTOM")
		(9 "F.Adhes" user "F.Adhesive")
		(11 "B.Adhes" user "B.Adhesive")
		(13 "F.Paste" user "Package Geometry/Pastemask Top")
		(15 "B.Paste" user "Package Geometry/Pastemask Bottom")
		(5 "F.SilkS" user "Ref Des/Silkscreen Top")
		(7 "B.SilkS" user "Ref Des/Silkscreen Bottom")
		(1 "F.Mask" user "Board Geometry/Soldermask Top")
		(3 "B.Mask" user "Board Geometry/Soldermask Bottom")
		(17 "Dwgs.User" user "User.Drawings")
		(19 "Cmts.User" user "User.Comments")
		(21 "Eco1.User" user "User.Eco1")
		(23 "Eco2.User" user "User.Eco2")
		(25 "Edge.Cuts" user "Board Geometry/Outline")
		(27 "Margin" user)
		(31 "F.CrtYd" user "Package Geometry/Place Bound Top")
		(29 "B.CrtYd" user "Package Geometry/Place Bound Bottom")
		(35 "F.Fab" user "Ref Des/Assembly Top")
		(33 "B.Fab" user "Ref Des/Assembly Bottom")
	)
	(footprint ""
		(layer "B.Cu")
		(at 167.200072 -290.199826 90)
		(property "Reference" "C1428"
			(at 0 0 90)
			(layer "B.SilkS")
			(hide yes)
			(effects
				(font
					(size 1.27 1.27)
				)
				(justify mirror)
			)
		)
		(property "Value" ""
			(at 0 0 90)
			(layer "B.Fab")
			(effects
				(font
					(size 1.27 1.27)
				)
				(justify mirror)
			)
		)
		(duplicate_pad_numbers_are_jumpers no)
		(fp_line
			(start 0.299974 -0.150114)
			(end -0.299974 -0.150114)
			(stroke
				(width 0.1)
				(type default)
			)
			(layer "B.Fab")
		)
		(fp_line
			(start -0.299974 -0.150114)
			(end -0.299974 0.150114)
			(stroke
				(width 0.1)
				(type default)
			)
			(layer "B.Fab")
		)
		(fp_line
			(start 0.299974 0.150114)
			(end 0.299974 -0.150114)
			(stroke
				(width 0.1)
				(type default)
			)
			(layer "B.Fab")
		)
		(fp_line
			(start -0.299974 0.150114)
			(end 0.299974 0.150114)
			(stroke
				(width 0.1)
				(type default)
			)
			(layer "B.Fab")
		)
		(pad "1" smd rect
			(at 0.2667 0 270)
			(size 0.3048 0.381)
			(layers "B.Cu" "B.Mask" "B.Paste")
			(net "P0V8_SERDES_VDDA_PEX1")
		)
		(pad "2" smd rect
			(at -0.2667 0 270)
			(size 0.3048 0.381)
			(layers "B.Cu" "B.Mask" "B.Paste")
			(net "GND")
		)
	)
	(footprint ""
		(layer "B.Cu")
		(at 59.649868 -299.699934 -90)
		(property "Reference" "C1214"
			(at 0 0 90)
			(layer "B.SilkS")
			(hide yes)
			(effects
				(font
					(size 1.27 1.27)
				)
				(justify mirror)
			)
		)
		(property "Value" ""
			(at 0 0 90)
			(layer "B.Fab")
			(effects
				(font
					(size 1.27 1.27)
				)
				(justify mirror)
			)
		)
		(duplicate_pad_numbers_are_jumpers no)
		(fp_line
			(start -0.299974 0.150114)
			(end 0.299974 0.150114)
			(stroke
				(width 0.1)
				(type default)
			)
			(layer "B.Fab")
		)
		(fp_line
			(start 0.299974 0.150114)
			(end 0.299974 -0.150114)
			(stroke
				(width 0.1)
				(type default)
			)
			(layer "B.Fab")
		)
		(fp_line
			(start -0.299974 -0.150114)
			(end -0.299974 0.150114)
			(stroke
				(width 0.1)
				(type default)
			)
			(layer "B.Fab")
		)
		(fp_line
			(start 0.299974 -0.150114)
			(end -0.299974 -0.150114)
			(stroke
				(width 0.1)
				(type default)
			)
			(layer "B.Fab")
		)
		(pad "1" smd rect
			(at 0.2667 0 90)
			(size 0.3048 0.381)
			(layers "B.Cu" "B.Mask" "B.Paste")
			(net "P0V8_SERDES_VDDA_PEX0")
		)
		(pad "2" smd rect
			(at -0.2667 0 90)
			(size 0.3048 0.381)
			(layers "B.Cu" "B.Mask" "B.Paste")
			(net "GND")
		)
	)
	(footprint ""
		(layer "B.Cu")
		(at 130.927602 -308.580028 90)
		(property "Reference" "C4248"
			(at 0 0 90)
			(layer "B.SilkS")
			(hide yes)
			(effects
				(font
					(size 1.27 1.27)
				)
				(justify mirror)
			)
		)
		(property "Value" ""
			(at 0 0 90)
			(layer "B.Fab")
			(effects
				(font
					(size 1.27 1.27)
				)
				(justify mirror)
			)
		)
		(duplicate_pad_numbers_are_jumpers no)
		(fp_line
			(start 1.2954 -0.5842)
			(end -1.2954 -0.5842)
			(stroke
				(width 0.1524)
				(type default)
			)
			(layer "B.SilkS")
		)
		(fp_line
			(start -1.2954 -0.5842)
			(end -1.2954 0.5842)
			(stroke
				(width 0.1524)
				(type default)
			)
			(layer "B.SilkS")
		)
		(fp_line
			(start 1.2954 0.5842)
			(end 1.2954 -0.5842)
			(stroke
				(width 0.1524)
				(type default)
			)
			(layer "B.SilkS")
		)
		(fp_line
			(start -1.2954 0.5842)
			(end 1.2954 0.5842)
			(stroke
				(width 0.1524)
				(type default)
			)
			(layer "B.SilkS")
		)
		(fp_line
			(start 0.8636 -0.4572)
			(end -0.8636 -0.4572)
			(stroke
				(width 0.1)
				(type default)
			)
			(layer "B.Fab")
		)
		(fp_line
			(start -0.8636 -0.4572)
			(end -0.8636 -0.4064)
			(stroke
				(width 0.1)
				(type default)
			)
			(layer "B.Fab")
		)
		(fp_line
			(start 1.1938 -0.4064)
			(end 0.8636 -0.4064)
			(stroke
				(width 0.1)
				(type default)
			)
			(layer "B.Fab")
		)
		(fp_line
			(start 0.8636 -0.4064)
			(end 0.8636 -0.4572)
			(stroke
				(width 0.1)
				(type default)
			)
			(layer "B.Fab")
		)
		(fp_line
			(start -0.8636 -0.4064)
			(end -1.1938 -0.4064)
			(stroke
				(width 0.1)
				(type default)
			)
			(layer "B.Fab")
		)
		(fp_line
			(start -1.1938 -0.4064)
			(end -1.1938 0.4064)
			(stroke
				(width 0.1)
				(type default)
			)
			(layer "B.Fab")
		)
		(fp_line
			(start 1.1938 0.4064)
			(end 1.1938 -0.4064)
			(stroke
				(width 0.1)
				(type default)
			)
			(layer "B.Fab")
		)
		(fp_line
			(start 0.8636 0.4064)
			(end 1.1938 0.4064)
			(stroke
				(width 0.1)
				(type default)
			)
			(layer "B.Fab")
		)
		(fp_line
			(start -0.8636 0.4064)
			(end -0.8636 0.4572)
			(stroke
				(width 0.1)
				(type default)
			)
			(layer "B.Fab")
		)
		(fp_line
			(start -1.1938 0.4064)
			(end -0.8636 0.4064)
			(stroke
				(width 0.1)
				(type default)
			)
			(layer "B.Fab")
		)
		(fp_line
			(start 0.8636 0.4572)
			(end 0.8636 0.4064)
			(stroke
				(width 0.1)
				(type default)
			)
			(layer "B.Fab")
		)
		(fp_line
			(start -0.8636 0.4572)
			(end 0.8636 0.4572)
			(stroke
				(width 0.1)
				(type default)
			)
			(layer "B.Fab")
		)
		(pad "1" smd rect
			(at 0.7366 0)
			(size 0.7112 0.8128)
			(layers "B.Cu" "B.Mask" "B.Paste")
			(net "P0V8_PEX1")
		)
		(pad "2" smd rect
			(at -0.7366 0)
			(size 0.7112 0.8128)
			(layers "B.Cu" "B.Mask" "B.Paste")
			(net "GND")
		)
	)
	(footprint ""
		(layer "B.Cu")
		(at 256.351532 -86.32952 180)
		(property "Reference" "C2643"
			(at 0 0 0)
			(layer "B.SilkS")
			(hide yes)
			(effects
				(font
					(size 1.27 1.27)
				)
				(justify mirror)
			)
		)
		(property "Value" ""
			(at 0 0 0)
			(layer "B.Fab")
			(effects
				(font
					(size 1.27 1.27)
				)
				(justify mirror)
			)
		)
		(duplicate_pad_numbers_are_jumpers no)
		(fp_line
			(start 0.7874 0.4064)
			(end 0.7874 -0.4064)
			(stroke
				(width 0.1524)
				(type default)
			)
			(layer "B.SilkS")
		)
		(fp_line
			(start 0.7874 -0.4064)
			(end -0.7874 -0.4064)
			(stroke
				(width 0.1524)
				(type default)
			)
			(layer "B.SilkS")
		)
		(fp_line
			(start -0.7874 0.4064)
			(end 0.7874 0.4064)
			(stroke
				(width 0.1524)
				(type default)
			)
			(layer "B.SilkS")
		)
		(fp_line
			(start -0.7874 -0.4064)
			(end -0.7874 0.4064)
			(stroke
				(width 0.1524)
				(type default)
			)
			(layer "B.SilkS")
		)
		(fp_line
			(start 0.67945 0.3048)
			(end 0.67945 -0.305054)
			(stroke
				(width 0.1)
				(type default)
			)
			(layer "B.Fab")
		)
		(fp_line
			(start 0.67945 -0.305054)
			(end 0.12065 -0.305054)
			(stroke
				(width 0.1)
				(type default)
			)
			(layer "B.Fab")
		)
		(fp_line
			(start 0.12065 0.3048)
			(end 0.67945 0.3048)
			(stroke
				(width 0.1)
				(type default)
			)
			(layer "B.Fab")
		)
		(fp_line
			(start 0.12065 0.2794)
			(end 0.12065 0.3048)
			(stroke
				(width 0.1)
				(type default)
			)
			(layer "B.Fab")
		)
		(fp_line
			(start 0.12065 -0.2794)
			(end -0.12065 -0.2794)
			(stroke
				(width 0.1)
				(type default)
			)
			(layer "B.Fab")
		)
		(fp_line
			(start 0.12065 -0.305054)
			(end 0.12065 -0.2794)
			(stroke
				(width 0.1)
				(type default)
			)
			(layer "B.Fab")
		)
		(fp_line
			(start -0.120396 0.3048)
			(end -0.120396 0.2794)
			(stroke
				(width 0.1)
				(type default)
			)
			(layer "B.Fab")
		)
		(fp_line
			(start -0.120396 0.2794)
			(end 0.12065 0.2794)
			(stroke
				(width 0.1)
				(type default)
			)
			(layer "B.Fab")
		)
		(fp_line
			(start -0.12065 -0.2794)
			(end -0.12065 -0.3048)
			(stroke
				(width 0.1)
				(type default)
			)
			(layer "B.Fab")
		)
		(fp_line
			(start -0.12065 -0.3048)
			(end -0.67945 -0.3048)
			(stroke
				(width 0.1)
				(type default)
			)
			(layer "B.Fab")
		)
		(fp_line
			(start -0.67945 0.3048)
			(end -0.120396 0.3048)
			(stroke
				(width 0.1)
				(type default)
			)
			(layer "B.Fab")
		)
		(fp_line
			(start -0.67945 -0.3048)
			(end -0.67945 0.3048)
			(stroke
				(width 0.1)
				(type default)
			)
			(layer "B.Fab")
		)
		(pad "1" smd circle
			(at 0.40005 0)
			(size 0 0)
			(layers "B.Cu" "B.Mask" "B.Paste")
			(net "P3V3_CLK_GEN_VDDA25M_CK440")
		)
		(pad "2" smd circle
			(at -0.40005 0)
			(size 0 0)
			(layers "B.Cu" "B.Mask" "B.Paste")
			(net "GND")
		)
	)
	(footprint ""
		(layer "B.Cu")
		(at 346.614242 -308.613556 90)
		(property "Reference" "C1670"
			(at 0 0 90)
			(layer "B.SilkS")
			(hide yes)
			(effects
				(font
					(size 1.27 1.27)
				)
				(justify mirror)
			)
		)
		(property "Value" ""
			(at 0 0 90)
			(layer "B.Fab")
			(effects
				(font
					(size 1.27 1.27)
				)
				(justify mirror)
			)
		)
		(duplicate_pad_numbers_are_jumpers no)
		(fp_line
			(start 1.2954 -0.5842)
			(end -1.2954 -0.5842)
			(stroke
				(width 0.1524)
				(type default)
			)
			(layer "B.SilkS")
		)
		(fp_line
			(start -1.2954 -0.5842)
			(end -1.2954 0.5842)
			(stroke
				(width 0.1524)
				(type default)
			)
			(layer "B.SilkS")
		)
		(fp_line
			(start 1.2954 0.5842)
			(end 1.2954 -0.5842)
			(stroke
				(width 0.1524)
				(type default)
			)
			(layer "B.SilkS")
		)
		(fp_line
			(start -1.2954 0.5842)
			(end 1.2954 0.5842)
			(stroke
				(width 0.1524)
				(type default)
			)
			(layer "B.SilkS")
		)
		(fp_line
			(start 0.8636 -0.4572)
			(end -0.8636 -0.4572)
			(stroke
				(width 0.1)
				(type default)
			)
			(layer "B.Fab")
		)
		(fp_line
			(start -0.8636 -0.4572)
			(end -0.8636 -0.4064)
			(stroke
				(width 0.1)
				(type default)
			)
			(layer "B.Fab")
		)
		(fp_line
			(start 1.1938 -0.4064)
			(end 0.8636 -0.4064)
			(stroke
				(width 0.1)
				(type default)
			)
			(layer "B.Fab")
		)
		(fp_line
			(start 0.8636 -0.4064)
			(end 0.8636 -0.4572)
			(stroke
				(width 0.1)
				(type default)
			)
			(layer "B.Fab")
		)
		(fp_line
			(start -0.8636 -0.4064)
			(end -1.1938 -0.4064)
			(stroke
				(width 0.1)
				(type default)
			)
			(layer "B.Fab")
		)
		(fp_line
			(start -1.1938 -0.4064)
			(end -1.1938 0.4064)
			(stroke
				(width 0.1)
				(type default)
			)
			(layer "B.Fab")
		)
		(fp_line
			(start 1.1938 0.4064)
			(end 1.1938 -0.4064)
			(stroke
				(width 0.1)
				(type default)
			)
			(layer "B.Fab")
		)
		(fp_line
			(start 0.8636 0.4064)
			(end 1.1938 0.4064)
			(stroke
				(width 0.1)
				(type default)
			)
			(layer "B.Fab")
		)
		(fp_line
			(start -0.8636 0.4064)
			(end -0.8636 0.4572)
			(stroke
				(width 0.1)
				(type default)
			)
			(layer "B.Fab")
		)
		(fp_line
			(start -1.1938 0.4064)
			(end -0.8636 0.4064)
			(stroke
				(width 0.1)
				(type default)
			)
			(layer "B.Fab")
		)
		(fp_line
			(start 0.8636 0.4572)
			(end 0.8636 0.4064)
			(stroke
				(width 0.1)
				(type default)
			)
			(layer "B.Fab")
		)
		(fp_line
			(start -0.8636 0.4572)
			(end 0.8636 0.4572)
			(stroke
				(width 0.1)
				(type default)
			)
			(layer "B.Fab")
		)
		(pad "1" smd rect
			(at 0.7366 0)
			(size 0.7112 0.8128)
			(layers "B.Cu" "B.Mask" "B.Paste")
			(net "P0V8_SERDES_VDDA_PEX2")
		)
		(pad "2" smd rect
			(at -0.7366 0)
			(size 0.7112 0.8128)
			(layers "B.Cu" "B.Mask" "B.Paste")
			(net "GND")
		)
	)
	(footprint ""
		(layer "B.Cu")
		(at 53.474874 -297.79976 90)
		(property "Reference" "C1121"
			(at 0 0 90)
			(layer "B.SilkS")
			(hide yes)
			(effects
				(font
					(size 1.27 1.27)
				)
				(justify mirror)
			)
		)
		(property "Value" ""
			(at 0 0 90)
			(layer "B.Fab")
			(effects
				(font
					(size 1.27 1.27)
				)
				(justify mirror)
			)
		)
		(duplicate_pad_numbers_are_jumpers no)
		(fp_line
			(start 0.299974 -0.150114)
			(end -0.299974 -0.150114)
			(stroke
				(width 0.1)
				(type default)
			)
			(layer "B.Fab")
		)
		(fp_line
			(start -0.299974 -0.150114)
			(end -0.299974 0.150114)
			(stroke
				(width 0.1)
				(type default)
			)
			(layer "B.Fab")
		)
		(fp_line
			(start 0.299974 0.150114)
			(end 0.299974 -0.150114)
			(stroke
				(width 0.1)
				(type default)
			)
			(layer "B.Fab")
		)
		(fp_line
			(start -0.299974 0.150114)
			(end 0.299974 0.150114)
			(stroke
				(width 0.1)
				(type default)
			)
			(layer "B.Fab")
		)
		(pad "1" smd rect
			(at 0.2667 0 270)
			(size 0.3048 0.381)
			(layers "B.Cu" "B.Mask" "B.Paste")
			(net "P0V8_PEX0")
		)
		(pad "2" smd rect
			(at -0.2667 0 270)
			(size 0.3048 0.381)
			(layers "B.Cu" "B.Mask" "B.Paste")
			(net "GND")
		)
	)
	(footprint ""
		(layer "B.Cu")
		(at 303.077626 -251.787406 90)
		(property "Reference" "R4098"
			(at 0 0 90)
			(layer "B.SilkS")
			(hide yes)
			(effects
				(font
					(size 1.27 1.27)
				)
				(justify mirror)
			)
		)
		(property "Value" ""
			(at 0 0 90)
			(layer "B.Fab")
			(effects
				(font
					(size 1.27 1.27)
				)
				(justify mirror)
			)
		)
		(duplicate_pad_numbers_are_jumpers no)
		(fp_line
			(start 0.7874 -0.4064)
			(end -0.7874 -0.4064)
			(stroke
				(width 0.1524)
				(type default)
			)
			(layer "B.SilkS")
		)
		(fp_line
			(start -0.7874 -0.4064)
			(end -0.7874 0.4064)
			(stroke
				(width 0.1524)
				(type default)
			)
			(layer "B.SilkS")
		)
		(fp_line
			(start 0.7874 0.4064)
			(end 0.7874 -0.4064)
			(stroke
				(width 0.1524)
				(type default)
			)
			(layer "B.SilkS")
		)
		(fp_line
			(start -0.7874 0.4064)
			(end 0.7874 0.4064)
			(stroke
				(width 0.1524)
				(type default)
			)
			(layer "B.SilkS")
		)
		(fp_line
			(start 0.67945 -0.305054)
			(end 0.12065 -0.305054)
			(stroke
				(width 0.1)
				(type default)
			)
			(layer "B.Fab")
		)
		(fp_line
			(start 0.12065 -0.305054)
			(end 0.12065 -0.2794)
			(stroke
				(width 0.1)
				(type default)
			)
			(layer "B.Fab")
		)
		(fp_line
			(start -0.12065 -0.3048)
			(end -0.67945 -0.3048)
			(stroke
				(width 0.1)
				(type default)
			)
			(layer "B.Fab")
		)
		(fp_line
			(start -0.67945 -0.3048)
			(end -0.67945 0.3048)
			(stroke
				(width 0.1)
				(type default)
			)
			(layer "B.Fab")
		)
		(fp_line
			(start 0.12065 -0.2794)
			(end -0.12065 -0.2794)
			(stroke
				(width 0.1)
				(type default)
			)
			(layer "B.Fab")
		)
		(fp_line
			(start -0.12065 -0.2794)
			(end -0.12065 -0.3048)
			(stroke
				(width 0.1)
				(type default)
			)
			(layer "B.Fab")
		)
		(fp_line
			(start 0.12065 0.2794)
			(end 0.12065 0.3048)
			(stroke
				(width 0.1)
				(type default)
			)
			(layer "B.Fab")
		)
		(fp_line
			(start -0.120396 0.2794)
			(end 0.12065 0.2794)
			(stroke
				(width 0.1)
				(type default)
			)
			(layer "B.Fab")
		)
		(fp_line
			(start 0.67945 0.3048)
			(end 0.67945 -0.305054)
			(stroke
				(width 0.1)
				(type default)
			)
			(layer "B.Fab")
		)
		(fp_line
			(start 0.12065 0.3048)
			(end 0.67945 0.3048)
			(stroke
				(width 0.1)
				(type default)
			)
			(layer "B.Fab")
		)
		(fp_line
			(start -0.120396 0.3048)
			(end -0.120396 0.2794)
			(stroke
				(width 0.1)
				(type default)
			)
			(layer "B.Fab")
		)
		(fp_line
			(start -0.67945 0.3048)
			(end -0.120396 0.3048)
			(stroke
				(width 0.1)
				(type default)
			)
			(layer "B.Fab")
		)
		(pad "1" smd circle
			(at 0.40005 0 270)
			(size 0 0)
			(layers "B.Cu" "B.Mask" "B.Paste")
			(net "SMB_MB_BMC_R_SCL")
		)
		(pad "2" smd circle
			(at -0.40005 0 270)
			(size 0 0)
			(layers "B.Cu" "B.Mask" "B.Paste")
			(net "P3V3_AUX")
		)
	)
	(footprint ""
		(layer "B.Cu")
		(at 213.106 -203.327 -90)
		(property "Reference" "R6308"
			(at 0 0 90)
			(layer "B.SilkS")
			(hide yes)
			(effects
				(font
					(size 1.27 1.27)
				)
				(justify mirror)
			)
		)
		(property "Value" ""
			(at 0 0 90)
			(layer "B.Fab")
			(effects
				(font
					(size 1.27 1.27)
				)
				(justify mirror)
			)
		)
		(duplicate_pad_numbers_are_jumpers no)
		(fp_line
			(start -0.7874 0.4064)
			(end 0.7874 0.4064)
			(stroke
				(width 0.1524)
				(type default)
			)
			(layer "B.SilkS")
		)
		(fp_line
			(start 0.7874 0.4064)
			(end 0.7874 -0.4064)
			(stroke
				(width 0.1524)
				(type default)
			)
			(layer "B.SilkS")
		)
		(fp_line
			(start -0.7874 -0.4064)
			(end -0.7874 0.4064)
			(stroke
				(width 0.1524)
				(type default)
			)
			(layer "B.SilkS")
		)
		(fp_line
			(start 0.7874 -0.4064)
			(end -0.7874 -0.4064)
			(stroke
				(width 0.1524)
				(type default)
			)
			(layer "B.SilkS")
		)
		(fp_line
			(start -0.67945 0.3048)
			(end -0.120396 0.3048)
			(stroke
				(width 0.1)
				(type default)
			)
			(layer "B.Fab")
		)
		(fp_line
			(start -0.120396 0.3048)
			(end -0.120396 0.2794)
			(stroke
				(width 0.1)
				(type default)
			)
			(layer "B.Fab")
		)
		(fp_line
			(start 0.12065 0.3048)
			(end 0.67945 0.3048)
			(stroke
				(width 0.1)
				(type default)
			)
			(layer "B.Fab")
		)
		(fp_line
			(start 0.67945 0.3048)
			(end 0.67945 -0.305054)
			(stroke
				(width 0.1)
				(type default)
			)
			(layer "B.Fab")
		)
		(fp_line
			(start -0.120396 0.2794)
			(end 0.12065 0.2794)
			(stroke
				(width 0.1)
				(type default)
			)
			(layer "B.Fab")
		)
		(fp_line
			(start 0.12065 0.2794)
			(end 0.12065 0.3048)
			(stroke
				(width 0.1)
				(type default)
			)
			(layer "B.Fab")
		)
		(fp_line
			(start -0.12065 -0.2794)
			(end -0.12065 -0.3048)
			(stroke
				(width 0.1)
				(type default)
			)
			(layer "B.Fab")
		)
		(fp_line
			(start 0.12065 -0.2794)
			(end -0.12065 -0.2794)
			(stroke
				(width 0.1)
				(type default)
			)
			(layer "B.Fab")
		)
		(fp_line
			(start -0.67945 -0.3048)
			(end -0.67945 0.3048)
			(stroke
				(width 0.1)
				(type default)
			)
			(layer "B.Fab")
		)
		(fp_line
			(start -0.12065 -0.3048)
			(end -0.67945 -0.3048)
			(stroke
				(width 0.1)
				(type default)
			)
			(layer "B.Fab")
		)
		(fp_line
			(start 0.12065 -0.305054)
			(end 0.12065 -0.2794)
			(stroke
				(width 0.1)
				(type default)
			)
			(layer "B.Fab")
		)
		(fp_line
			(start 0.67945 -0.305054)
			(end 0.12065 -0.305054)
			(stroke
				(width 0.1)
				(type default)
			)
			(layer "B.Fab")
		)
		(pad "1" smd circle
			(at 0.40005 0 90)
			(size 0 0)
			(layers "B.Cu" "B.Mask" "B.Paste")
			(net "SMB_NIC5_LS_SDA")
		)
		(pad "2" smd circle
			(at -0.40005 0 90)
			(size 0 0)
			(layers "B.Cu" "B.Mask" "B.Paste")
			(net "SMB_NIC5_LS_R_SDA")
		)
	)
)
